(kicad_pcb
	(version 20260206)
	(generator "pcbnew")
	(generator_version "10.0")
	(general
		(thickness 1.6)
		(legacy_teardrops no)
	)
	(paper "A4")
	(title_block
		(title "04192023_DAF0TMB3IC0_F0TG_MB_C_brd_V02_OCP.brd")
		(comment 1 "Grand Teton / footprints 5112-5119 of 8354")
	)
	(layers
		(0 "F.Cu" signal "TOP")
		(4 "In1.Cu" signal "GND")
		(6 "In2.Cu" signal "IN1")
		(8 "In3.Cu" signal "GND1")
		(10 "In4.Cu" signal "IN2")
		(12 "In5.Cu" signal "GND2")
		(14 "In6.Cu" signal "IN3")
		(16 "In7.Cu" signal "GND3")
		(18 "In8.Cu" signal "VCC")
		(20 "In9.Cu" signal "VCC1")
		(22 "In10.Cu" signal "GND4")
		(24 "In11.Cu" signal "IN4")
		(26 "In12.Cu" signal "GND5")
		(28 "In13.Cu" signal "IN5")
		(30 "In14.Cu" signal "GND6")
		(32 "In15.Cu" signal "IN6")
		(34 "In16.Cu" signal "GND7")
		(2 "B.Cu" signal "BOTTOM")
		(9 "F.Adhes" user "F.Adhesive")
		(11 "B.Adhes" user "B.Adhesive")
		(13 "F.Paste" user "Package Geometry/Pastemask Top")
		(15 "B.Paste" user "Package Geometry/Pastemask Bottom")
		(5 "F.SilkS" user "Ref Des/Silkscreen Top")
		(7 "B.SilkS" user "Ref Des/Silkscreen Bottom")
		(1 "F.Mask" user "Board Geometry/Soldermask Top")
		(3 "B.Mask" user "Board Geometry/Soldermask Bottom")
		(17 "Dwgs.User" user "User.Drawings")
		(19 "Cmts.User" user "User.Comments")
		(21 "Eco1.User" user "User.Eco1")
		(23 "Eco2.User" user "User.Eco2")
		(25 "Edge.Cuts" user "Board Geometry/Outline")
		(27 "Margin" user)
		(31 "F.CrtYd" user "Package Geometry/Place Bound Top")
		(29 "B.CrtYd" user "Package Geometry/Place Bound Bottom")
		(35 "F.Fab" user "Ref Des/Assembly Top")
		(33 "B.Fab" user "Ref Des/Assembly Bottom")
	)
	(footprint ""
		(layer "B.Cu")
		(at 90.590878 -189.461648 90)
		(property "Reference" "PC276"
			(at 6.607556 -0.649986 270)
			(unlocked yes)
			(layer "B.SilkS")
			(effects
				(font
					(size 0.7874 0.5842)
					(thickness 0.1524)
				)
				(justify left mirror)
			)
		)
		(property "Value" ""
			(at 0 0 90)
			(layer "B.Fab")
			(effects
				(font
					(size 1.27 1.27)
				)
				(justify mirror)
			)
		)
		(duplicate_pad_numbers_are_jumpers no)
		(fp_line
			(start 4.533392 -2.249932)
			(end -4.533392 -2.249932)
			(stroke
				(width 0.1524)
				(type default)
			)
			(layer "B.SilkS")
		)
		(fp_line
			(start -4.533392 -2.249932)
			(end -4.533392 2.249932)
			(stroke
				(width 0.1524)
				(type default)
			)
			(layer "B.SilkS")
		)
		(fp_line
			(start 4.533392 2.249932)
			(end 4.533392 -2.249932)
			(stroke
				(width 0.1524)
				(type default)
			)
			(layer "B.SilkS")
		)
		(fp_line
			(start -4.533392 2.249932)
			(end 4.533392 2.249932)
			(stroke
				(width 0.1524)
				(type default)
			)
			(layer "B.SilkS")
		)
		(fp_rect
			(start 4.533392 -2.326132)
			(end 5.39242 2.326132)
			(stroke
				(width 0)
				(type default)
			)
			(fill yes)
			(layer "B.SilkS")
		)
		(fp_line
			(start 3.750056 -2.249932)
			(end -3.750056 -2.249932)
			(stroke
				(width 0.1)
				(type default)
			)
			(layer "B.Fab")
		)
		(fp_line
			(start -3.750056 -2.249932)
			(end -3.750056 2.249932)
			(stroke
				(width 0.1)
				(type default)
			)
			(layer "B.Fab")
		)
		(fp_line
			(start 3.750056 2.249932)
			(end 3.750056 -2.249932)
			(stroke
				(width 0.1)
				(type default)
			)
			(layer "B.Fab")
		)
		(fp_line
			(start -3.750056 2.249932)
			(end 3.750056 2.249932)
			(stroke
				(width 0.1)
				(type default)
			)
			(layer "B.Fab")
		)
		(fp_text user "-"
			(at -4.8514 -0.14605 90)
			(unlocked yes)
			(layer "B.SilkS")
			(effects
				(font
					(size 1.905 1.4224)
					(thickness 0.1524)
				)
				(justify left mirror)
			)
		)
		(fp_text user "+"
			(at 6.322314 0.786384 0)
			(unlocked yes)
			(layer "B.SilkS")
			(effects
				(font
					(size 1.905 1.4224)
					(thickness 0.1524)
				)
				(justify left mirror)
			)
		)
		(fp_text user "-"
			(at -4.8514 -0.14605 90)
			(unlocked yes)
			(layer "B.Fab")
			(effects
				(font
					(size 1.905 1.4224)
					(thickness 0.1524)
				)
				(justify left mirror)
			)
		)
		(fp_text user "+"
			(at 6.322314 0.786384 0)
			(unlocked yes)
			(layer "B.Fab")
			(effects
				(font
					(size 1.905 1.4224)
					(thickness 0.1524)
				)
				(justify left mirror)
			)
		)
		(pad "1" smd rect
			(at 3.199892 0 270)
			(size 2.413 2.8194)
			(layers "B.Cu" "B.Mask" "B.Paste")
			(net "PVDDCR_CPU0_P1")
		)
		(pad "2" smd rect
			(at -3.199892 0 270)
			(size 2.413 2.8194)
			(layers "B.Cu" "B.Mask" "B.Paste")
			(net "GND")
		)
	)
	(footprint ""
		(layer "B.Cu")
		(at 109.577124 -261.748016 90)
		(property "Reference" "C2125"
			(at 0 0 90)
			(layer "B.SilkS")
			(hide yes)
			(effects
				(font
					(size 1.27 1.27)
				)
				(justify mirror)
			)
		)
		(property "Value" ""
			(at 0 0 90)
			(layer "B.Fab")
			(effects
				(font
					(size 1.27 1.27)
				)
				(justify mirror)
			)
		)
		(duplicate_pad_numbers_are_jumpers no)
		(fp_line
			(start 0.7874 -0.4064)
			(end -0.7874 -0.4064)
			(stroke
				(width 0.1524)
				(type default)
			)
			(layer "B.SilkS")
		)
		(fp_line
			(start -0.7874 -0.4064)
			(end -0.7874 0.4064)
			(stroke
				(width 0.1524)
				(type default)
			)
			(layer "B.SilkS")
		)
		(fp_line
			(start 0.7874 0.4064)
			(end 0.7874 -0.4064)
			(stroke
				(width 0.1524)
				(type default)
			)
			(layer "B.SilkS")
		)
		(fp_line
			(start -0.7874 0.4064)
			(end 0.7874 0.4064)
			(stroke
				(width 0.1524)
				(type default)
			)
			(layer "B.SilkS")
		)
		(fp_line
			(start 0.67945 -0.305054)
			(end 0.12065 -0.305054)
			(stroke
				(width 0.1)
				(type default)
			)
			(layer "B.Fab")
		)
		(fp_line
			(start 0.12065 -0.305054)
			(end 0.12065 -0.2794)
			(stroke
				(width 0.1)
				(type default)
			)
			(layer "B.Fab")
		)
		(fp_line
			(start -0.12065 -0.3048)
			(end -0.67945 -0.3048)
			(stroke
				(width 0.1)
				(type default)
			)
			(layer "B.Fab")
		)
		(fp_line
			(start -0.67945 -0.3048)
			(end -0.67945 0.3048)
			(stroke
				(width 0.1)
				(type default)
			)
			(layer "B.Fab")
		)
		(fp_line
			(start 0.12065 -0.2794)
			(end -0.12065 -0.2794)
			(stroke
				(width 0.1)
				(type default)
			)
			(layer "B.Fab")
		)
		(fp_line
			(start -0.12065 -0.2794)
			(end -0.12065 -0.3048)
			(stroke
				(width 0.1)
				(type default)
			)
			(layer "B.Fab")
		)
		(fp_line
			(start 0.12065 0.2794)
			(end 0.12065 0.3048)
			(stroke
				(width 0.1)
				(type default)
			)
			(layer "B.Fab")
		)
		(fp_line
			(start -0.120396 0.2794)
			(end 0.12065 0.2794)
			(stroke
				(width 0.1)
				(type default)
			)
			(layer "B.Fab")
		)
		(fp_line
			(start 0.67945 0.3048)
			(end 0.67945 -0.305054)
			(stroke
				(width 0.1)
				(type default)
			)
			(layer "B.Fab")
		)
		(fp_line
			(start 0.12065 0.3048)
			(end 0.67945 0.3048)
			(stroke
				(width 0.1)
				(type default)
			)
			(layer "B.Fab")
		)
		(fp_line
			(start -0.120396 0.3048)
			(end -0.120396 0.2794)
			(stroke
				(width 0.1)
				(type default)
			)
			(layer "B.Fab")
		)
		(fp_line
			(start -0.67945 0.3048)
			(end -0.120396 0.3048)
			(stroke
				(width 0.1)
				(type default)
			)
			(layer "B.Fab")
		)
		(pad "1" smd circle
			(at 0.40005 0 270)
			(size 0 0)
			(layers "B.Cu" "B.Mask" "B.Paste")
			(net "PVDD11_S3_P1")
		)
		(pad "2" smd circle
			(at -0.40005 0 270)
			(size 0 0)
			(layers "B.Cu" "B.Mask" "B.Paste")
			(net "GND")
		)
	)
	(footprint ""
		(layer "B.Cu")
		(at 407.806144 -395.148562 90)
		(property "Reference" "C787"
			(at 0 0 90)
			(layer "B.SilkS")
			(hide yes)
			(effects
				(font
					(size 1.27 1.27)
				)
				(justify mirror)
			)
		)
		(property "Value" ""
			(at 0 0 90)
			(layer "B.Fab")
			(effects
				(font
					(size 1.27 1.27)
				)
				(justify mirror)
			)
		)
		(duplicate_pad_numbers_are_jumpers no)
		(fp_line
			(start 0.299974 -0.150114)
			(end -0.299974 -0.150114)
			(stroke
				(width 0.1)
				(type default)
			)
			(layer "B.Fab")
		)
		(fp_line
			(start -0.299974 -0.150114)
			(end -0.299974 0.150114)
			(stroke
				(width 0.1)
				(type default)
			)
			(layer "B.Fab")
		)
		(fp_line
			(start 0.299974 0.150114)
			(end 0.299974 -0.150114)
			(stroke
				(width 0.1)
				(type default)
			)
			(layer "B.Fab")
		)
		(fp_line
			(start -0.299974 0.150114)
			(end 0.299974 0.150114)
			(stroke
				(width 0.1)
				(type default)
			)
			(layer "B.Fab")
		)
		(pad "1" smd rect
			(at 0.2667 0 270)
			(size 0.3048 0.381)
			(layers "B.Cu" "B.Mask" "B.Paste")
			(net "P0V9_CPU0_RT2_2A_2D")
		)
		(pad "2" smd rect
			(at -0.2667 0 270)
			(size 0.3048 0.381)
			(layers "B.Cu" "B.Mask" "B.Paste")
			(net "GND")
		)
	)
	(footprint ""
		(layer "B.Cu")
		(at 393.352274 -392.957558)
		(property "Reference" "L22"
			(at 0 0 0)
			(layer "B.SilkS")
			(hide yes)
			(effects
				(font
					(size 1.27 1.27)
				)
				(justify mirror)
			)
		)
		(property "Value" ""
			(at 0 0 0)
			(layer "B.Fab")
			(effects
				(font
					(size 1.27 1.27)
				)
				(justify mirror)
			)
		)
		(duplicate_pad_numbers_are_jumpers no)
		(fp_line
			(start -1.63576 -0.8128)
			(end -1.63576 0.8128)
			(stroke
				(width 0.1524)
				(type default)
			)
			(layer "B.SilkS")
		)
		(fp_line
			(start -1.63576 0.8128)
			(end 1.63576 0.8128)
			(stroke
				(width 0.1524)
				(type default)
			)
			(layer "B.SilkS")
		)
		(fp_line
			(start 1.63576 -0.8128)
			(end -1.63576 -0.8128)
			(stroke
				(width 0.1524)
				(type default)
			)
			(layer "B.SilkS")
		)
		(fp_line
			(start 1.63576 -0.8128)
			(end 1.63576 0.8128)
			(stroke
				(width 0.1524)
				(type default)
			)
			(layer "B.SilkS")
		)
		(fp_line
			(start -1.560576 -0.738632)
			(end 1.56083 -0.738632)
			(stroke
				(width 0.1)
				(type default)
			)
			(layer "B.Fab")
		)
		(fp_line
			(start -1.560576 0.7366)
			(end -1.560576 -0.738632)
			(stroke
				(width 0.1)
				(type default)
			)
			(layer "B.Fab")
		)
		(fp_line
			(start -1.524 0.7366)
			(end -1.560576 0.7366)
			(stroke
				(width 0.1)
				(type default)
			)
			(layer "B.Fab")
		)
		(fp_line
			(start 1.524 0.7366)
			(end -1.524 0.7366)
			(stroke
				(width 0.1)
				(type default)
			)
			(layer "B.Fab")
		)
		(fp_line
			(start 1.56083 -0.738632)
			(end 1.56083 0.7366)
			(stroke
				(width 0.1)
				(type default)
			)
			(layer "B.Fab")
		)
		(fp_line
			(start 1.56083 0.7366)
			(end 1.524 0.7366)
			(stroke
				(width 0.1)
				(type default)
			)
			(layer "B.Fab")
		)
		(pad "1" smd rect
			(at 0.94996 0)
			(size 1.1176 1.3716)
			(layers "B.Cu" "B.Mask" "B.Paste")
			(net "P1V8_CPU0_RT_1D")
		)
		(pad "2" smd rect
			(at -0.94996 0)
			(size 1.1176 1.3716)
			(layers "B.Cu" "B.Mask" "B.Paste")
			(net "P1V8_CPU0_RT3_1A")
		)
	)
	(footprint ""
		(layer "B.Cu")
		(at 435.549802 -13.120116 180)
		(property "Reference" "C1237"
			(at 0 0 0)
			(layer "B.SilkS")
			(hide yes)
			(effects
				(font
					(size 1.27 1.27)
				)
				(justify mirror)
			)
		)
		(property "Value" ""
			(at 0 0 0)
			(layer "B.Fab")
			(effects
				(font
					(size 1.27 1.27)
				)
				(justify mirror)
			)
		)
		(duplicate_pad_numbers_are_jumpers no)
		(fp_line
			(start 0.7874 0.4064)
			(end 0.7874 -0.4064)
			(stroke
				(width 0.1524)
				(type default)
			)
			(layer "B.SilkS")
		)
		(fp_line
			(start 0.7874 -0.4064)
			(end -0.7874 -0.4064)
			(stroke
				(width 0.1524)
				(type default)
			)
			(layer "B.SilkS")
		)
		(fp_line
			(start -0.7874 0.4064)
			(end 0.7874 0.4064)
			(stroke
				(width 0.1524)
				(type default)
			)
			(layer "B.SilkS")
		)
		(fp_line
			(start -0.7874 -0.4064)
			(end -0.7874 0.4064)
			(stroke
				(width 0.1524)
				(type default)
			)
			(layer "B.SilkS")
		)
		(fp_line
			(start 0.67945 0.3048)
			(end 0.67945 -0.305054)
			(stroke
				(width 0.1)
				(type default)
			)
			(layer "B.Fab")
		)
		(fp_line
			(start 0.67945 -0.305054)
			(end 0.12065 -0.305054)
			(stroke
				(width 0.1)
				(type default)
			)
			(layer "B.Fab")
		)
		(fp_line
			(start 0.12065 0.3048)
			(end 0.67945 0.3048)
			(stroke
				(width 0.1)
				(type default)
			)
			(layer "B.Fab")
		)
		(fp_line
			(start 0.12065 0.2794)
			(end 0.12065 0.3048)
			(stroke
				(width 0.1)
				(type default)
			)
			(layer "B.Fab")
		)
		(fp_line
			(start 0.12065 -0.2794)
			(end -0.12065 -0.2794)
			(stroke
				(width 0.1)
				(type default)
			)
			(layer "B.Fab")
		)
		(fp_line
			(start 0.12065 -0.305054)
			(end 0.12065 -0.2794)
			(stroke
				(width 0.1)
				(type default)
			)
			(layer "B.Fab")
		)
		(fp_line
			(start -0.120396 0.3048)
			(end -0.120396 0.2794)
			(stroke
				(width 0.1)
				(type default)
			)
			(layer "B.Fab")
		)
		(fp_line
			(start -0.120396 0.2794)
			(end 0.12065 0.2794)
			(stroke
				(width 0.1)
				(type default)
			)
			(layer "B.Fab")
		)
		(fp_line
			(start -0.12065 -0.2794)
			(end -0.12065 -0.3048)
			(stroke
				(width 0.1)
				(type default)
			)
			(layer "B.Fab")
		)
		(fp_line
			(start -0.12065 -0.3048)
			(end -0.67945 -0.3048)
			(stroke
				(width 0.1)
				(type default)
			)
			(layer "B.Fab")
		)
		(fp_line
			(start -0.67945 0.3048)
			(end -0.120396 0.3048)
			(stroke
				(width 0.1)
				(type default)
			)
			(layer "B.Fab")
		)
		(fp_line
			(start -0.67945 -0.3048)
			(end -0.67945 0.3048)
			(stroke
				(width 0.1)
				(type default)
			)
			(layer "B.Fab")
		)
		(pad "1" smd circle
			(at 0.40005 0)
			(size 0 0)
			(layers "B.Cu" "B.Mask" "B.Paste")
			(net "P3V3_OCP_SFF")
		)
		(pad "2" smd circle
			(at -0.40005 0)
			(size 0 0)
			(layers "B.Cu" "B.Mask" "B.Paste")
			(net "GND")
		)
	)
	(footprint ""
		(layer "B.Cu")
		(at 17.90065 -388.789926 90)
		(property "Reference" "PC6615_1"
			(at 0 0 90)
			(layer "B.SilkS")
			(hide yes)
			(effects
				(font
					(size 1.27 1.27)
				)
				(justify mirror)
			)
		)
		(property "Value" ""
			(at 0 0 90)
			(layer "B.Fab")
			(effects
				(font
					(size 1.27 1.27)
				)
				(justify mirror)
			)
		)
		(duplicate_pad_numbers_are_jumpers no)
		(fp_line
			(start 1.524 -0.762)
			(end -1.524 -0.762)
			(stroke
				(width 0.1524)
				(type default)
			)
			(layer "B.SilkS")
		)
		(fp_line
			(start -1.524 -0.762)
			(end -1.524 0.762)
			(stroke
				(width 0.1524)
				(type default)
			)
			(layer "B.SilkS")
		)
		(fp_line
			(start 1.524 0.762)
			(end 1.524 -0.762)
			(stroke
				(width 0.1524)
				(type default)
			)
			(layer "B.SilkS")
		)
		(fp_line
			(start -1.524 0.762)
			(end 1.524 0.762)
			(stroke
				(width 0.1524)
				(type default)
			)
			(layer "B.SilkS")
		)
		(fp_line
			(start 1.1049 -0.724916)
			(end 1.1049 0.724916)
			(stroke
				(width 0.1)
				(type default)
			)
			(layer "B.Fab")
		)
		(fp_line
			(start -1.1049 -0.724916)
			(end 1.1049 -0.724916)
			(stroke
				(width 0.1)
				(type default)
			)
			(layer "B.Fab")
		)
		(fp_line
			(start 1.1049 0.724916)
			(end -1.1049 0.724916)
			(stroke
				(width 0.1)
				(type default)
			)
			(layer "B.Fab")
		)
		(fp_line
			(start -1.1049 0.724916)
			(end -1.1049 -0.724916)
			(stroke
				(width 0.1)
				(type default)
			)
			(layer "B.Fab")
		)
		(pad "1" smd rect
			(at 0.889 0 90)
			(size 1.016 1.27)
			(layers "B.Cu" "B.Mask" "B.Paste")
			(net "SW_P12V_AUX_P0V9_RETIMER_CPU1_FLT")
		)
		(pad "2" smd rect
			(at -0.889 0 90)
			(size 1.016 1.27)
			(layers "B.Cu" "B.Mask" "B.Paste")
			(net "GND")
		)
	)
	(footprint ""
		(layer "B.Cu")
		(at 348.151958 -263.521952)
		(property "Reference" "C2597"
			(at 0 0 0)
			(layer "B.SilkS")
			(hide yes)
			(effects
				(font
					(size 1.27 1.27)
				)
				(justify mirror)
			)
		)
		(property "Value" ""
			(at 0 0 0)
			(layer "B.Fab")
			(effects
				(font
					(size 1.27 1.27)
				)
				(justify mirror)
			)
		)
		(duplicate_pad_numbers_are_jumpers no)
		(fp_line
			(start -0.7874 -0.4064)
			(end -0.7874 0.4064)
			(stroke
				(width 0.1524)
				(type default)
			)
			(layer "B.SilkS")
		)
		(fp_line
			(start -0.7874 0.4064)
			(end 0.7874 0.4064)
			(stroke
				(width 0.1524)
				(type default)
			)
			(layer "B.SilkS")
		)
		(fp_line
			(start 0.7874 -0.4064)
			(end -0.7874 -0.4064)
			(stroke
				(width 0.1524)
				(type default)
			)
			(layer "B.SilkS")
		)
		(fp_line
			(start 0.7874 0.4064)
			(end 0.7874 -0.4064)
			(stroke
				(width 0.1524)
				(type default)
			)
			(layer "B.SilkS")
		)
		(fp_line
			(start -0.67945 -0.3048)
			(end -0.67945 0.3048)
			(stroke
				(width 0.1)
				(type default)
			)
			(layer "B.Fab")
		)
		(fp_line
			(start -0.67945 0.3048)
			(end -0.120396 0.3048)
			(stroke
				(width 0.1)
				(type default)
			)
			(layer "B.Fab")
		)
		(fp_line
			(start -0.12065 -0.3048)
			(end -0.67945 -0.3048)
			(stroke
				(width 0.1)
				(type default)
			)
			(layer "B.Fab")
		)
		(fp_line
			(start -0.12065 -0.2794)
			(end -0.12065 -0.3048)
			(stroke
				(width 0.1)
				(type default)
			)
			(layer "B.Fab")
		)
		(fp_line
			(start -0.120396 0.2794)
			(end 0.12065 0.2794)
			(stroke
				(width 0.1)
				(type default)
			)
			(layer "B.Fab")
		)
		(fp_line
			(start -0.120396 0.3048)
			(end -0.120396 0.2794)
			(stroke
				(width 0.1)
				(type default)
			)
			(layer "B.Fab")
		)
		(fp_line
			(start 0.12065 -0.305054)
			(end 0.12065 -0.2794)
			(stroke
				(width 0.1)
				(type default)
			)
			(layer "B.Fab")
		)
		(fp_line
			(start 0.12065 -0.2794)
			(end -0.12065 -0.2794)
			(stroke
				(width 0.1)
				(type default)
			)
			(layer "B.Fab")
		)
		(fp_line
			(start 0.12065 0.2794)
			(end 0.12065 0.3048)
			(stroke
				(width 0.1)
				(type default)
			)
			(layer "B.Fab")
		)
		(fp_line
			(start 0.12065 0.3048)
			(end 0.67945 0.3048)
			(stroke
				(width 0.1)
				(type default)
			)
			(layer "B.Fab")
		)
		(fp_line
			(start 0.67945 -0.305054)
			(end 0.12065 -0.305054)
			(stroke
				(width 0.1)
				(type default)
			)
			(layer "B.Fab")
		)
		(fp_line
			(start 0.67945 0.3048)
			(end 0.67945 -0.305054)
			(stroke
				(width 0.1)
				(type default)
			)
			(layer "B.Fab")
		)
		(pad "1" smd circle
			(at 0.40005 0 180)
			(size 0 0)
			(layers "B.Cu" "B.Mask" "B.Paste")
			(net "PVDDIO_P0")
		)
		(pad "2" smd circle
			(at -0.40005 0 180)
			(size 0 0)
			(layers "B.Cu" "B.Mask" "B.Paste")
			(net "GND")
		)
	)
	(footprint ""
		(layer "B.Cu")
		(at 79.932784 -408.517344 90)
		(property "Reference" "C6682"
			(at 0 0 90)
			(layer "B.SilkS")
			(hide yes)
			(effects
				(font
					(size 1.27 1.27)
				)
				(justify mirror)
			)
		)
		(property "Value" ""
			(at 0 0 90)
			(layer "B.Fab")
			(effects
				(font
					(size 1.27 1.27)
				)
				(justify mirror)
			)
		)
		(duplicate_pad_numbers_are_jumpers no)
		(fp_line
			(start 0.299974 -0.150114)
			(end -0.299974 -0.150114)
			(stroke
				(width 0.1)
				(type default)
			)
			(layer "B.Fab")
		)
		(fp_line
			(start -0.299974 -0.150114)
			(end -0.299974 0.150114)
			(stroke
				(width 0.1)
				(type default)
			)
			(layer "B.Fab")
		)
		(fp_line
			(start 0.299974 0.150114)
			(end 0.299974 -0.150114)
			(stroke
				(width 0.1)
				(type default)
			)
			(layer "B.Fab")
		)
		(fp_line
			(start -0.299974 0.150114)
			(end 0.299974 0.150114)
			(stroke
				(width 0.1)
				(type default)
			)
			(layer "B.Fab")
		)
		(pad "1" smd rect
			(at 0.2667 0 270)
			(size 0.3048 0.381)
			(layers "B.Cu" "B.Mask" "B.Paste")
			(net "P5E_CPU1_P1_TX_BUF_C_DN<10>")
		)
		(pad "2" smd rect
			(at -0.2667 0 270)
			(size 0.3048 0.381)
			(layers "B.Cu" "B.Mask" "B.Paste")
			(net "P5E_CPU1_P1_TX_BUF_DN<10>")
		)
	)
)
